# S9S_MB_2U (Grand Teton) — schematic netlist excerpt (pin names and nets, part order shuffled) for the footprints in the layout excerpt that follows; sources: Cadence DE-HDL packaged netlist, KiCad conversion of 03242023_DA0F0TMBIJ0_F0T_Motherboard_J_brd_V01_OCP.brd

R3108  Q_RES  0 5% CHIP  pkg 0402LF  page 234 : A = SMB_2_BMC_GPU_SDA ; B = SMB_2_BMC_GPU_R_SDA
PJ48  Q_SHORT  EMPTY  pkg SM  page 296 : \1\ = VSENSE_PVCCD_HV_CPU1_DP ; \2\ = SH_PVCCD_HV_CPU1
C234  Q_CAP  10UF 6.3V 20% X6S  pkg C0402  page 77 : A = PVCCIN_CPU1 ; B = GND

(kicad_pcb
	(version 20260206)
	(generator "pcbnew")
	(generator_version "10.0")
	(general
		(thickness 1.6)
		(legacy_teardrops no)
	)
	(paper "A4")
	(title_block
		(title "03242023_DA0F0TMBIJ0_F0T_Motherboard_J_brd_V01_OCP.brd")
		(comment 1 "Grand Teton / footprints 113-115 of 6105")
	)
	(layers
		(0 "F.Cu" signal "TOP")
		(4 "In1.Cu" signal "GND")
		(6 "In2.Cu" signal "IN1")
		(8 "In3.Cu" signal "GND1")
		(10 "In4.Cu" signal "IN2")
		(12 "In5.Cu" signal "GND2")
		(14 "In6.Cu" signal "IN3")
		(16 "In7.Cu" signal "GND3")
		(18 "In8.Cu" signal "VCC")
		(20 "In9.Cu" signal "VCC1")
		(22 "In10.Cu" signal "GND4")
		(24 "In11.Cu" signal "IN4")
		(26 "In12.Cu" signal "GND5")
		(28 "In13.Cu" signal "IN5")
		(30 "In14.Cu" signal "GND6")
		(32 "In15.Cu" signal "IN6")
		(34 "In16.Cu" signal "GND7")
		(2 "B.Cu" signal "BOTTOM")
		(9 "F.Adhes" user "F.Adhesive")
		(11 "B.Adhes" user "B.Adhesive")
		(13 "F.Paste" user "Package Geometry/Pastemask Top")
		(15 "B.Paste" user "Package Geometry/Pastemask Bottom")
		(5 "F.SilkS" user "Ref Des/Silkscreen Top")
		(7 "B.SilkS" user "Ref Des/Silkscreen Bottom")
		(1 "F.Mask" user "Board Geometry/Soldermask Top")
		(3 "B.Mask" user "Board Geometry/Soldermask Bottom")
		(17 "Dwgs.User" user "User.Drawings")
		(19 "Cmts.User" user "User.Comments")
		(21 "Eco1.User" user "User.Eco1")
		(23 "Eco2.User" user "User.Eco2")
		(25 "Edge.Cuts" user "Board Geometry/Outline")
		(27 "Margin" user)
		(31 "F.CrtYd" user "Package Geometry/Place Bound Top")
		(29 "B.CrtYd" user "Package Geometry/Place Bound Bottom")
		(35 "F.Fab" user "Ref Des/Assembly Top")
		(33 "B.Fab" user "Ref Des/Assembly Bottom")
	)
	(footprint ""
		(layer "F.Cu")
		(at 20.802346 -161.06394 90)
		(property "Reference" "PJ48"
			(at -2.825242 -1.264666 0)
			(unlocked yes)
			(layer "F.SilkS")
			(effects
				(font
					(size 0.7874 0.5842)
					(thickness 0.1524)
				)
				(justify left)
			)
		)
		(property "Value" ""
			(at 0 0 90)
			(layer "F.Fab")
			(effects
				(font
					(size 1.27 1.27)
				)
			)
		)
		(duplicate_pad_numbers_are_jumpers no)
		(pad "1" smd circle
			(at -0.7493 0 180)
			(size 0 0)
			(layers "F.Cu" "F.Mask" "F.Paste")
			(net "VSENSE_PVCCD_HV_CPU1_DP")
		)
		(pad "2" smd rect
			(at 0.7493 0)
			(size 0.7112 0.8128)
			(layers "F.Cu" "F.Mask" "F.Paste")
			(net "SH_PVCCD_HV_CPU1")
		)
		(zone
			(layer "F.Cu")
			(hatch none 0.5)
			(connect_pads
				(clearance 0)
			)
			(min_thickness 0.25)
			(keepout
				(tracks allowed)
				(vias not_allowed)
				(pads allowed)
				(copperpour not_allowed)
				(footprints allowed)
			)
			(placement
				(enabled no)
				(sheetname "")
			)
			(fill
				(thermal_gap 0.5)
				(thermal_bridge_width 0.5)
				(island_removal_mode 0)
			)
			(polygon
				(pts
					(xy 20.395946 -159.88284) (xy 21.213572 -159.88284) (xy 21.213572 -162.27044) (xy 20.395946 -162.27044)
				)
			)
		)
	)
	(footprint ""
		(layer "F.Cu")
		(at 32.780478 -439.720228)
		(property "Reference" "R3108"
			(at 0 0 0)
			(layer "F.SilkS")
			(hide yes)
			(effects
				(font
					(size 1.27 1.27)
				)
			)
		)
		(property "Value" ""
			(at 0 0 0)
			(layer "F.Fab")
			(effects
				(font
					(size 1.27 1.27)
				)
			)
		)
		(duplicate_pad_numbers_are_jumpers no)
		(fp_line
			(start -0.7874 -0.4064)
			(end 0.7874 -0.4064)
			(stroke
				(width 0.1524)
				(type default)
			)
			(layer "F.SilkS")
		)
		(fp_line
			(start -0.7874 0.4064)
			(end -0.7874 -0.4064)
			(stroke
				(width 0.1524)
				(type default)
			)
			(layer "F.SilkS")
		)
		(fp_line
			(start 0.7874 -0.4064)
			(end 0.7874 0.4064)
			(stroke
				(width 0.1524)
				(type default)
			)
			(layer "F.SilkS")
		)
		(fp_line
			(start 0.7874 0.4064)
			(end -0.7874 0.4064)
			(stroke
				(width 0.1524)
				(type default)
			)
			(layer "F.SilkS")
		)
		(fp_line
			(start -0.67945 -0.305054)
			(end -0.12065 -0.305054)
			(stroke
				(width 0.1)
				(type default)
			)
			(layer "F.Fab")
		)
		(fp_line
			(start -0.67945 0.3048)
			(end -0.67945 -0.305054)
			(stroke
				(width 0.1)
				(type default)
			)
			(layer "F.Fab")
		)
		(fp_line
			(start -0.12065 -0.305054)
			(end -0.12065 -0.2794)
			(stroke
				(width 0.1)
				(type default)
			)
			(layer "F.Fab")
		)
		(fp_line
			(start -0.12065 -0.2794)
			(end 0.12065 -0.2794)
			(stroke
				(width 0.1)
				(type default)
			)
			(layer "F.Fab")
		)
		(fp_line
			(start -0.12065 0.2794)
			(end -0.12065 0.3048)
			(stroke
				(width 0.1)
				(type default)
			)
			(layer "F.Fab")
		)
		(fp_line
			(start -0.12065 0.3048)
			(end -0.67945 0.3048)
			(stroke
				(width 0.1)
				(type default)
			)
			(layer "F.Fab")
		)
		(fp_line
			(start 0.120396 0.2794)
			(end -0.12065 0.2794)
			(stroke
				(width 0.1)
				(type default)
			)
			(layer "F.Fab")
		)
		(fp_line
			(start 0.120396 0.3048)
			(end 0.120396 0.2794)
			(stroke
				(width 0.1)
				(type default)
			)
			(layer "F.Fab")
		)
		(fp_line
			(start 0.12065 -0.3048)
			(end 0.67945 -0.3048)
			(stroke
				(width 0.1)
				(type default)
			)
			(layer "F.Fab")
		)
		(fp_line
			(start 0.12065 -0.2794)
			(end 0.12065 -0.3048)
			(stroke
				(width 0.1)
				(type default)
			)
			(layer "F.Fab")
		)
		(fp_line
			(start 0.67945 -0.3048)
			(end 0.67945 0.3048)
			(stroke
				(width 0.1)
				(type default)
			)
			(layer "F.Fab")
		)
		(fp_line
			(start 0.67945 0.3048)
			(end 0.120396 0.3048)
			(stroke
				(width 0.1)
				(type default)
			)
			(layer "F.Fab")
		)
		(pad "1" smd circle
			(at -0.40005 0)
			(size 0 0)
			(layers "F.Cu" "F.Mask" "F.Paste")
			(net "SMB_2_BMC_GPU_SDA")
		)
		(pad "2" smd circle
			(at 0.40005 0)
			(size 0 0)
			(layers "F.Cu" "F.Mask" "F.Paste")
			(net "SMB_2_BMC_GPU_R_SDA")
		)
	)
	(footprint ""
		(layer "F.Cu")
		(at 119.508016 -249.320558 -90)
		(property "Reference" "C234"
			(at 0 0 270)
			(layer "F.SilkS")
			(hide yes)
			(effects
				(font
					(size 1.27 1.27)
				)
			)
		)
		(property "Value" ""
			(at 0 0 270)
			(layer "F.Fab")
			(effects
				(font
					(size 1.27 1.27)
				)
			)
		)
		(duplicate_pad_numbers_are_jumpers no)
		(fp_line
			(start -0.7874 0.4064)
			(end -0.7874 -0.4064)
			(stroke
				(width 0.1524)
				(type default)
			)
			(layer "F.SilkS")
		)
		(fp_line
			(start 0.7874 0.4064)
			(end -0.7874 0.4064)
			(stroke
				(width 0.1524)
				(type default)
			)
			(layer "F.SilkS")
		)
		(fp_line
			(start -0.7874 -0.4064)
			(end 0.7874 -0.4064)
			(stroke
				(width 0.1524)
				(type default)
			)
			(layer "F.SilkS")
		)
		(fp_line
			(start 0.7874 -0.4064)
			(end 0.7874 0.4064)
			(stroke
				(width 0.1524)
				(type default)
			)
			(layer "F.SilkS")
		)
		(fp_line
			(start -0.67945 0.3048)
			(end -0.67945 -0.305054)
			(stroke
				(width 0.1)
				(type default)
			)
			(layer "F.Fab")
		)
		(fp_line
			(start -0.12065 0.3048)
			(end -0.67945 0.3048)
			(stroke
				(width 0.1)
				(type default)
			)
			(layer "F.Fab")
		)
		(fp_line
			(start 0.120396 0.3048)
			(end 0.120396 0.2794)
			(stroke
				(width 0.1)
				(type default)
			)
			(layer "F.Fab")
		)
		(fp_line
			(start 0.67945 0.3048)
			(end 0.120396 0.3048)
			(stroke
				(width 0.1)
				(type default)
			)
			(layer "F.Fab")
		)
		(fp_line
			(start -0.12065 0.2794)
			(end -0.12065 0.3048)
			(stroke
				(width 0.1)
				(type default)
			)
			(layer "F.Fab")
		)
		(fp_line
			(start 0.120396 0.2794)
			(end -0.12065 0.2794)
			(stroke
				(width 0.1)
				(type default)
			)
			(layer "F.Fab")
		)
		(fp_line
			(start -0.12065 -0.2794)
			(end 0.12065 -0.2794)
			(stroke
				(width 0.1)
				(type default)
			)
			(layer "F.Fab")
		)
		(fp_line
			(start 0.12065 -0.2794)
			(end 0.12065 -0.3048)
			(stroke
				(width 0.1)
				(type default)
			)
			(layer "F.Fab")
		)
		(fp_line
			(start 0.12065 -0.3048)
			(end 0.67945 -0.3048)
			(stroke
				(width 0.1)
				(type default)
			)
			(layer "F.Fab")
		)
		(fp_line
			(start 0.67945 -0.3048)
			(end 0.67945 0.3048)
			(stroke
				(width 0.1)
				(type default)
			)
			(layer "F.Fab")
		)
		(fp_line
			(start -0.67945 -0.305054)
			(end -0.12065 -0.305054)
			(stroke
				(width 0.1)
				(type default)
			)
			(layer "F.Fab")
		)
		(fp_line
			(start -0.12065 -0.305054)
			(end -0.12065 -0.2794)
			(stroke
				(width 0.1)
				(type default)
			)
			(layer "F.Fab")
		)
		(pad "1" smd circle
			(at -0.40005 0 270)
			(size 0 0)
			(layers "F.Cu" "F.Mask" "F.Paste")
			(net "PVCCIN_CPU1")
		)
		(pad "2" smd circle
			(at 0.40005 0 270)
			(size 0 0)
			(layers "F.Cu" "F.Mask" "F.Paste")
			(net "GND")
		)
	)
)
